FILE_TYPE=LIBRARY_PARTS;
primitive 'TTL2G07','TTL2G07_SOT23LF','TTL2G07_SC70';
  pin
    '1A':
      PIN_NUMBER='(1)';
      INPUT_LOAD='(-0.01,0.01)';
    '2A':
      PIN_NUMBER='(3)';
      INPUT_LOAD='(-0.01,0.01)';
    '2Y':
      PIN_NUMBER='(4)';
      OUTPUT_LOAD='(1.0,-1.0)';
    '1Y':
      PIN_NUMBER='(6)';
      OUTPUT_LOAD='(1.0,-1.0)';
  end_pin;
  body
    PART_NAME='TTL2G07';
    BODY_NAME='TTL2G07';
    PHYS_DES_PREFIX='U';
    POWER_PINS='(GND:2)';
    POWER_PINS='(VCC:5)';
  end_body;
end_primitive;

END.
